FILE_TYPE = MACRO_DRAWING;
SET COLOR_WIRE YELLOW;
SET COLOR_PROP MONO;
SET COLOR_DOT WHITE;
SET COLOR_ARC YELLOW;
SET COLOR_BODY GREEN;
SET COLOR_NOTE MONO;
SET PROP_DISPLAY VALUE;
SET PAGE_NUMBER P183;
FORCEADD OFFPAGE..2
(4500 -600);
FORCEPROP 2 LAST $XR1 119 
J 0
(4809 -600);
DISPLAY 0.638298 (4809 -600);
PAINT MONO (4809 -600);
FORCEPROP 2 LAST $XR0 190 
J 0
(4689 -600);
DISPLAY 0.638298 (4689 -600);
PAINT MONO (4689 -600);
FORCEPROP 2 LAST PATH I1
J 0
(4825 -550);
DISPLAY 1.021277 (4825 -550);
PAINT ORANGE (4825 -550);
DISPLAY INVISIBLE (4825 -550);
FORCEPROP 2 LAST CDS_LIB mstr_standard
J 0
(4500 -600);
PAINT ORANGE (4500 -600);
DISPLAY INVISIBLE (4500 -600);
FORCEPROP 1 LAST COMMENT_BODY TRUE
J 0
(4455 -695);
DISPLAY 0.872340 (4455 -695);
PAINT GREEN (4455 -695);
DISPLAY INVISIBLE (4455 -695);
FORCEPROP 1 LAST OFFPAGE TRUE
J 0
(4825 -725);
DISPLAY 0.872340 (4825 -725);
PAINT GREEN (4825 -725);
DISPLAY INVISIBLE (4825 -725);
FORCEADD P3V3_STBY..1
(3150 -150);
FORCEPROP 3 LASTPIN (3150 -200) SIG_NAME P3V3_STBY\g
J 0
(3160 -190);
DISPLAY 0.659574 (3160 -190);
PAINT MONO (3160 -190);
DISPLAY INVISIBLE (3160 -190);
FORCEPROP 1 LAST SIZE 1B
J 0
(3195 -128);
DISPLAY 0.340426 (3195 -128);
PAINT GREEN (3195 -128);
DISPLAY INVISIBLE (3195 -128);
FORCEPROP 2 LAST CDS_LIB mstr_symbols
J 0
(3150 -150);
PAINT MONO (3150 -150);
DISPLAY INVISIBLE (3150 -150);
FORCEPROP 1 LAST BODY_TYPE PLUMBING
J 0
(3105 -193);
DISPLAY 0.340426 (3105 -193);
PAINT GREEN (3105 -193);
DISPLAY INVISIBLE (3105 -193);
FORCEPROP 1 LAST VOLTAGE 3.3V
J 0
(3105 -193);
DISPLAY 0.340426 (3105 -193);
PAINT SKYBLUE (3105 -193);
DISPLAY INVISIBLE (3105 -193);
FORCEPROP 1 LAST HDL_POWER P3V3_STBY
J 0
(2850 -275);
DISPLAY 0.872340 (2850 -275);
PAINT ORANGE (2850 -275);
DISPLAY INVISIBLE (2850 -275);
FORCEPROP 1 LAST PATH I2
J 0
(3195 -148);
DISPLAY 0.340426 (3195 -148);
PAINT GREEN (3195 -148);
DISPLAY INVISIBLE (3195 -148);
FORCEADD RES..2
(3150 -400);
FORCEPROP 1 LASTPIN (3150 -500) $PN 2
J 0
(3155 -490);
DISPLAY 0.617021 (3155 -490);
PAINT ORANGE (3155 -490);
FORCEPROP 1 LAST TOLERANCE 1%
J 0
(3195 -375);
DISPLAY 0.617021 (3195 -375);
PAINT SKYBLUE (3195 -375);
FORCEPROP 1 LAST WATTAGE 1/16W
J 0
(3190 -425);
DISPLAY 0.617021 (3190 -425);
PAINT SKYBLUE (3190 -425);
FORCEPROP 1 LAST MATERIAL CHIP
J 0
(3190 -475);
DISPLAY 0.617021 (3190 -475);
PAINT SKYBLUE (3190 -475);
FORCEPROP 1 LAST PACK_TYPE 0402
J 0
(3190 -575);
DISPLAY 0.617021 (3190 -575);
PAINT SKYBLUE (3190 -575);
FORCEPROP 1 LAST VALUE 4.75K
J 0
(3195 -325);
DISPLAY 0.617021 (3195 -325);
PAINT SKYBLUE (3195 -325);
FORCEPROP 1 LAST LOCATION R9F55
J 0
(3195 -275);
DISPLAY 0.617021 (3195 -275);
PAINT AQUA (3195 -275);
FORCEPROP 1 LASTPIN (3150 -300) $PN 1
J 0
(3155 -338);
DISPLAY 0.617021 (3155 -338);
PAINT ORANGE (3155 -338);
FORCEPROP 1 LAST PART_NUMBER G21796-072
J 0
(3190 -525);
DISPLAY 0.617021 (3190 -525);
PAINT BLUE (3190 -525);
FORCEPROP 1 LAST PATH I3
J 0
(3200 -225);
DISPLAY 0.978723 (3200 -225);
PAINT WHITE (3200 -225);
DISPLAY INVISIBLE (3200 -225);
FORCEPROP 2 LAST CDS_LIB mstr_discrete
J 0
(3150 -400);
PAINT MONO (3150 -400);
DISPLAY INVISIBLE (3150 -400);
FORCEPROP 2 LAST ROOM LBG
J 0
(3100 -250);
DISPLAY 1.021277 (3100 -250);
PAINT ORANGE (3100 -250);
DISPLAY INVISIBLE (3100 -250);
FORCEPROP 2 LAST BOM_COST LBG_UART
J 0
(3100 -200);
DISPLAY 1.021277 (3100 -200);
PAINT ORANGE (3100 -200);
DISPLAY INVISIBLE (3100 -200);
FORCEPROP 2 LAST CDS_LOCATION R9F55
J 0
(3195 -275);
DISPLAY 0.617021 (3195 -275);
PAINT AQUA (3195 -275);
DISPLAY INVISIBLE (3195 -275);
FORCEPROP 2 LAST SEC 1
J 0
(3200 -175);
DISPLAY 0.680851 (3200 -175);
PAINT MONO (3200 -175);
DISPLAY INVISIBLE (3200 -175);
FORCEPROP 2 LAST SEC_TYPE 0402
J 0
(3200 -175);
DISPLAY 1.021277 (3200 -175);
PAINT ORANGE (3200 -175);
DISPLAY INVISIBLE (3200 -175);
FORCEPROP 0 LAST CDS_SEC 1
J 0
(3200 -225);
PAINT MONO (3200 -225);
DISPLAY INVISIBLE (3200 -225);
FORCEADD INTEL_CORP_BPAGE..1
(5800 -1575);
FORCEPROP 1 LAST CDS_CON_LAST_MODIFIED Fri Jun 16 17:49:08 2017
J 0
(4375 -1250);
DISPLAY 1.361702 (4375 -1250);
PAINT GREEN (4375 -1250);
DISPLAY INVISIBLE (4375 -1250);
FORCEPROP 1 LAST CUSTOM_TXT_CDS <CURRENT_DESIGN_SHEET> OF <TOTAL_DESIGN_SHEETS>
J 0
(5300 -1550);
PAINT ORANGE (5300 -1550);
FORCEPROP 1 LAST CUSTOM_TXT_CDS <CON_LAST_MODIFIED>
J 0
(1800 -1475);
PAINT ORANGE (1800 -1475);
FORCEPROP 2 LAST CUSTOM_TXT_CDS <XR_PAGE_TITLE>
J 0
(-2090 3675);
DISPLAY 0.638298 (-2090 3675);
PAINT PINK (-2090 3675);
DISPLAY INVISIBLE (-2090 3675);
FORCEPROP 1 LAST SCH_TITLE I2C/SPI TO UART BRIDGE CONTROLLER
J 0
(-2150 -1525);
DISPLAY 1.212766 (-2150 -1525);
PAINT ORANGE (-2150 -1525);
FORCEPROP 1 LAST COMMENT_BODY TRUE
J 0
(5812 -1563);
DISPLAY 0.617021 (5812 -1563);
PAINT GREEN (5812 -1563);
DISPLAY INVISIBLE (5812 -1563);
FORCEPROP 2 LAST CDS_LIB mstr_symbols
J 0
(5800 -1575);
DISPLAY 1.361702 (5800 -1575);
PAINT ORANGE (5800 -1575);
DISPLAY INVISIBLE (5800 -1575);
FORCEPROP 2 LAST PAGE_BORDER TRUE
J 0
(-2090 3675);
DISPLAY 0.851064 (-2090 3675);
PAINT PINK (-2090 3675);
DISPLAY INVISIBLE (-2090 3675);
FORCEPROP 2 LAST CDS_XR_PAGE_TITLE CR-183 : @BASEBOARD_FAB2_LIB.BASEBOARD_FAB2(SCH_1):PAGE183
J 0
(-2090 3675);
DISPLAY 0.638298 (-2090 3675);
PAINT PINK (-2090 3675);
DISPLAY INVISIBLE (-2090 3675);
WIRE 16 -1 (3150 -300)(3150 -200);
WIRE 16 -1 (3150 -500)(3150 -600);
WIRE 16 -1 (4450 -600)(3150 -600);
FORCEPROP 0 LAST SIG_NAME FM_UART_ALERT_N
J 0
(3940 -590);
DISPLAY 0.617021 (3940 -590);
PAINT ORANGE (3940 -590);
WIRE 3 682 (-450 2775)(-450 125);
WIRE 3 682 (4275 125)(-450 125);
WIRE 3 682 (-450 2775)(4275 2775);
WIRE 3 682 (4275 2775)(4275 125);
FORCENOTE
LEAVE PU RES FOR  GPIO
(3150 -675) 0;
DISPLAY LEFT (3150 -675);
DISPLAY 1.021277 (3150 -675);
PAINT PURPLE (3150 -675);
FORCENOTE
TP FAB1 DELETE PI7C9X1172 AND RELATED COMPONENT (NO USE IE) 0118
(400 350) 0;
DISPLAY LEFT (400 350);
DISPLAY 1.021277 (400 350);
PAINT RED (400 350);
QUIT
